# SCM (Grand Teton) — schematic netlist excerpt (pin names and nets, part order shuffled) for the footprints in the layout excerpt that follows; sources: Cadence DE-HDL packaged netlist, KiCad conversion of 12092022_DA0F0TMDCD0_F0T_Management_Board_D_brd_V3_OCP.brd

R512  Q_RES  33.2 1% CHIP  pkg 0402LF  page 32 : A = JTAG_SCM_TDI ; B = JTAG_SCM_PLD_TDI

X24  TP_TDR_4P_FTS  TP_TDR_4P_DIP EMPTY  pkg TH  page 60
  S1  = TDR_DIFF_100_BOT_DN
  P1  = GND_P1
  P2  = GND_P1
  S2  = TDR_DIFF_100_BOT_DP

(kicad_pcb
	(version 20260206)
	(generator "pcbnew")
	(generator_version "10.0")
	(general
		(thickness 1.6)
		(legacy_teardrops no)
	)
	(paper "A4")
	(title_block
		(title "12092022_DA0F0TMDCD0_F0T_Management_Board_D_brd_V3_OCP.brd")
		(comment 1 "Grand Teton / footprints 688-689 of 1440")
	)
	(layers
		(0 "F.Cu" signal "TOP")
		(4 "In1.Cu" signal "GND")
		(6 "In2.Cu" signal "IN1")
		(8 "In3.Cu" signal "GND1")
		(10 "In4.Cu" signal "IN2")
		(12 "In5.Cu" signal "VCC")
		(14 "In6.Cu" signal "VCC1")
		(16 "In7.Cu" signal "IN3")
		(18 "In8.Cu" signal "GND2")
		(20 "In9.Cu" signal "IN4")
		(22 "In10.Cu" signal "GND3")
		(2 "B.Cu" signal "BOTTOM")
		(9 "F.Adhes" user "F.Adhesive")
		(11 "B.Adhes" user "B.Adhesive")
		(13 "F.Paste" user "Package Geometry/Pastemask Top")
		(15 "B.Paste" user "Package Geometry/Pastemask Bottom")
		(5 "F.SilkS" user "Ref Des/Silkscreen Top")
		(7 "B.SilkS" user "Ref Des/Silkscreen Bottom")
		(1 "F.Mask" user "Board Geometry/Soldermask Top")
		(3 "B.Mask" user "Board Geometry/Soldermask Bottom")
		(17 "Dwgs.User" user "User.Drawings")
		(19 "Cmts.User" user "User.Comments")
		(21 "Eco1.User" user "User.Eco1")
		(23 "Eco2.User" user "User.Eco2")
		(25 "Edge.Cuts" user "Board Geometry/Outline")
		(27 "Margin" user)
		(31 "F.CrtYd" user "Package Geometry/Place Bound Top")
		(29 "B.CrtYd" user "Package Geometry/Place Bound Bottom")
		(35 "F.Fab" user "Ref Des/Assembly Top")
		(33 "B.Fab" user "Ref Des/Assembly Bottom")
	)
	(footprint ""
		(layer "F.Cu")
		(at 114.554 112.776 -90)
		(property "Reference" "X24"
			(at -1.81483 3.0353 0)
			(unlocked yes)
			(layer "F.SilkS")
			(effects
				(font
					(size 0.7874 0.5842)
					(thickness 0.1524)
				)
				(justify left)
			)
		)
		(property "Value" ""
			(at 0 0 270)
			(layer "F.Fab")
			(effects
				(font
					(size 1.27 1.27)
				)
			)
		)
		(property "Device Type" "TP_TDR_4P_FTS_TH-TP_TDR_4P_DIPA"
			(at 1.30175 1.27 0)
			(unlocked yes)
			(layer "F.Fab")
			(hide yes)
			(effects
				(font
					(size 0.635 0.4064)
					(thickness 0.1524)
				)
			)
		)
		(property "User Part Number" "N_A"
			(at 1.30175 1.27 0)
			(unlocked yes)
			(layer "Cmts.User")
			(hide yes)
			(effects
				(font
					(size 0.635 0.4064)
					(thickness 0.1524)
				)
			)
		)
		(duplicate_pad_numbers_are_jumpers no)
		(fp_line
			(start 0 3.81)
			(end 2.54 3.81)
			(stroke
				(width 0.1524)
				(type default)
			)
			(layer "F.SilkS")
		)
		(fp_line
			(start 2.54 3.81)
			(end 2.54 3.6703)
			(stroke
				(width 0.1524)
				(type default)
			)
			(layer "F.SilkS")
		)
		(fp_line
			(start 0 3.175)
			(end 0 3.81)
			(stroke
				(width 0.1524)
				(type default)
			)
			(layer "F.SilkS")
		)
		(fp_line
			(start 2.54 1.4097)
			(end 2.54 1.1303)
			(stroke
				(width 0.1524)
				(type default)
			)
			(layer "F.SilkS")
		)
		(fp_line
			(start 0 0.635)
			(end 0 1.905)
			(stroke
				(width 0.1524)
				(type default)
			)
			(layer "F.SilkS")
		)
		(fp_line
			(start 2.54 -1.1303)
			(end 2.54 -1.27)
			(stroke
				(width 0.1524)
				(type default)
			)
			(layer "F.SilkS")
		)
		(fp_line
			(start 0 -1.27)
			(end 0 -0.635)
			(stroke
				(width 0.1524)
				(type default)
			)
			(layer "F.SilkS")
		)
		(fp_line
			(start 2.54 -1.27)
			(end 0 -1.27)
			(stroke
				(width 0.1524)
				(type default)
			)
			(layer "F.SilkS")
		)
		(fp_poly
			(pts
				(xy -0.761746 0) (xy -2.285746 -0.762) (xy -2.285746 0.762)
			)
			(stroke
				(width 0)
				(type default)
			)
			(fill yes)
			(layer "F.SilkS")
		)
		(fp_line
			(start 0 3.81)
			(end 2.54 3.81)
			(stroke
				(width 0.1)
				(type default)
			)
			(layer "F.Fab")
		)
		(fp_line
			(start 2.54 3.81)
			(end 2.54 -1.27)
			(stroke
				(width 0.1)
				(type default)
			)
			(layer "F.Fab")
		)
		(fp_line
			(start 0 -1.27)
			(end 0 3.81)
			(stroke
				(width 0.1)
				(type default)
			)
			(layer "F.Fab")
		)
		(fp_line
			(start 2.54 -1.27)
			(end 0 -1.27)
			(stroke
				(width 0.1)
				(type default)
			)
			(layer "F.Fab")
		)
		(fp_poly
			(pts
				(xy -0.761746 0) (xy -2.285746 -0.762) (xy -2.285746 0.762)
			)
			(stroke
				(width 0)
				(type default)
			)
			(fill yes)
			(layer "F.Fab")
		)
		(pad "1" thru_hole circle
			(at 0 0 270)
			(size 1.0033 1.0033)
			(drill 0.249936)
			(layers "*.Cu" "*.Mask")
			(remove_unused_layers no)
			(net "TDR_DIFF_100_BOT_DN")
			(clearance 0.10795)
			(thermal_gap 0.10795)
			(padstack
				(mode front_inner_back)
				(layer "Inner"
					(shape circle)
					(size 0.8001 0.8001)
					(clearance 0.1524)
				)
				(layer "B.Cu"
					(shape circle)
					(size 1.0033 1.0033)
					(clearance 0.10795)
				)
			)
		)
		(pad "2" thru_hole circle
			(at 2.54 0 270)
			(size 1.9939 1.9939)
			(drill 0.249936)
			(layers "*.Cu" "*.Mask")
			(remove_unused_layers no)
			(net "GND_P1")
			(clearance 0.10795)
			(thermal_gap 0.10795)
			(padstack
				(mode front_inner_back)
				(layer "Inner"
					(shape circle)
					(size 0.8001 0.8001)
					(clearance 0.1524)
				)
				(layer "B.Cu"
					(shape circle)
					(size 1.9939 1.9939)
					(clearance 0.10795)
				)
			)
		)
		(pad "3" thru_hole circle
			(at 2.54 2.54 270)
			(size 1.9939 1.9939)
			(drill 0.249936)
			(layers "*.Cu" "*.Mask")
			(remove_unused_layers no)
			(net "GND_P1")
			(clearance 0.10795)
			(thermal_gap 0.10795)
			(padstack
				(mode front_inner_back)
				(layer "Inner"
					(shape circle)
					(size 0.8001 0.8001)
					(clearance 0.1524)
				)
				(layer "B.Cu"
					(shape circle)
					(size 1.9939 1.9939)
					(clearance 0.10795)
				)
			)
		)
		(pad "4" thru_hole circle
			(at 0 2.54 270)
			(size 1.0033 1.0033)
			(drill 0.249936)
			(layers "*.Cu" "*.Mask")
			(remove_unused_layers no)
			(net "TDR_DIFF_100_BOT_DP")
			(clearance 0.10795)
			(thermal_gap 0.10795)
			(padstack
				(mode front_inner_back)
				(layer "Inner"
					(shape circle)
					(size 0.8001 0.8001)
					(clearance 0.1524)
				)
				(layer "B.Cu"
					(shape circle)
					(size 1.0033 1.0033)
					(clearance 0.10795)
				)
			)
		)
	)
	(footprint ""
		(layer "F.Cu")
		(at 64.9732 -25.0444 180)
		(property "Reference" "R512"
			(at 0 0 180)
			(layer "F.SilkS")
			(hide yes)
			(effects
				(font
					(size 1.27 1.27)
				)
			)
		)
		(property "Value" ""
			(at 0 0 180)
			(layer "F.Fab")
			(effects
				(font
					(size 1.27 1.27)
				)
			)
		)
		(duplicate_pad_numbers_are_jumpers no)
		(fp_line
			(start 0.7874 0.4064)
			(end -0.7874 0.4064)
			(stroke
				(width 0.1524)
				(type default)
			)
			(layer "F.SilkS")
		)
		(fp_line
			(start 0.7874 -0.4064)
			(end 0.7874 0.4064)
			(stroke
				(width 0.1524)
				(type default)
			)
			(layer "F.SilkS")
		)
		(fp_line
			(start -0.7874 0.4064)
			(end -0.7874 -0.4064)
			(stroke
				(width 0.1524)
				(type default)
			)
			(layer "F.SilkS")
		)
		(fp_line
			(start -0.7874 -0.4064)
			(end 0.7874 -0.4064)
			(stroke
				(width 0.1524)
				(type default)
			)
			(layer "F.SilkS")
		)
		(fp_line
			(start 0.67945 0.3048)
			(end 0.120396 0.3048)
			(stroke
				(width 0.1)
				(type default)
			)
			(layer "F.Fab")
		)
		(fp_line
			(start 0.67945 -0.3048)
			(end 0.67945 0.3048)
			(stroke
				(width 0.1)
				(type default)
			)
			(layer "F.Fab")
		)
		(fp_line
			(start 0.12065 -0.2794)
			(end 0.12065 -0.3048)
			(stroke
				(width 0.1)
				(type default)
			)
			(layer "F.Fab")
		)
		(fp_line
			(start 0.12065 -0.3048)
			(end 0.67945 -0.3048)
			(stroke
				(width 0.1)
				(type default)
			)
			(layer "F.Fab")
		)
		(fp_line
			(start 0.120396 0.3048)
			(end 0.120396 0.2794)
			(stroke
				(width 0.1)
				(type default)
			)
			(layer "F.Fab")
		)
		(fp_line
			(start 0.120396 0.2794)
			(end -0.12065 0.2794)
			(stroke
				(width 0.1)
				(type default)
			)
			(layer "F.Fab")
		)
		(fp_line
			(start -0.12065 0.3048)
			(end -0.67945 0.3048)
			(stroke
				(width 0.1)
				(type default)
			)
			(layer "F.Fab")
		)
		(fp_line
			(start -0.12065 0.2794)
			(end -0.12065 0.3048)
			(stroke
				(width 0.1)
				(type default)
			)
			(layer "F.Fab")
		)
		(fp_line
			(start -0.12065 -0.2794)
			(end 0.12065 -0.2794)
			(stroke
				(width 0.1)
				(type default)
			)
			(layer "F.Fab")
		)
		(fp_line
			(start -0.12065 -0.305054)
			(end -0.12065 -0.2794)
			(stroke
				(width 0.1)
				(type default)
			)
			(layer "F.Fab")
		)
		(fp_line
			(start -0.67945 0.3048)
			(end -0.67945 -0.305054)
			(stroke
				(width 0.1)
				(type default)
			)
			(layer "F.Fab")
		)
		(fp_line
			(start -0.67945 -0.305054)
			(end -0.12065 -0.305054)
			(stroke
				(width 0.1)
				(type default)
			)
			(layer "F.Fab")
		)
		(pad "1" smd circle
			(at -0.40005 0 180)
			(size 0 0)
			(layers "F.Cu" "F.Mask" "F.Paste")
			(net "JTAG_SCM_TDI")
		)
		(pad "2" smd circle
			(at 0.40005 0 180)
			(size 0 0)
			(layers "F.Cu" "F.Mask" "F.Paste")
			(net "JTAG_SCM_PLD_TDI")
		)
	)
)
